(kicad_pcb
	(version 20260206)
	(generator "pcbnew")
	(generator_version "10.0")
	(general
		(thickness 1.6)
		(legacy_teardrops no)
	)
	(paper "A4")
	(title_block
		(title "Bryce Canyon_SCC_16316-1_OCP.brd")
		(comment 1 "Bryce Canyon / footprints 452-459 of 1561")
	)
	(layers
		(0 "F.Cu" signal "TOP")
		(4 "In1.Cu" signal "L2GND")
		(6 "In2.Cu" signal "L3")
		(8 "In3.Cu" signal "L4VCC")
		(10 "In4.Cu" signal "L5VCC")
		(12 "In5.Cu" signal "L6")
		(14 "In6.Cu" signal "L7GND")
		(2 "B.Cu" signal "BOTTOM")
		(9 "F.Adhes" user "F.Adhesive")
		(11 "B.Adhes" user "B.Adhesive")
		(13 "F.Paste" user "Package Geometry/Pastemask Top")
		(15 "B.Paste" user "Package Geometry/Pastemask Bottom")
		(5 "F.SilkS" user "Ref Des/Silkscreen Top")
		(7 "B.SilkS" user "Ref Des/Silkscreen Bottom")
		(1 "F.Mask" user "Board Geometry/Soldermask Top")
		(3 "B.Mask" user "Board Geometry/Soldermask Bottom")
		(17 "Dwgs.User" user "User.Drawings")
		(19 "Cmts.User" user "User.Comments")
		(21 "Eco1.User" user "User.Eco1")
		(23 "Eco2.User" user "User.Eco2")
		(25 "Edge.Cuts" user "Board Geometry/Outline")
		(27 "Margin" user)
		(31 "F.CrtYd" user "Package Geometry/Place Bound Top")
		(29 "B.CrtYd" user "Package Geometry/Place Bound Bottom")
		(35 "F.Fab" user "Ref Des/Assembly Top")
		(33 "B.Fab" user "Ref Des/Assembly Bottom")
	)
	(footprint ""
		(layer "F.Cu")
		(at 62.4332 -72.7202 180)
		(property "Reference" "R419"
			(at 0 0 180)
			(layer "F.SilkS")
			(hide yes)
			(effects
				(font
					(size 1.27 1.27)
				)
			)
		)
		(property "Value" "1KR2F-3-GP"
			(at 0.064008 -3.993896 180)
			(unlocked yes)
			(layer "F.Fab")
			(hide yes)
			(effects
				(font
					(size 1.016 1.016)
					(thickness 0.1524)
				)
			)
		)
		(property "Device Type" "R402H16"
			(at 0.064008 -5.517896 180)
			(unlocked yes)
			(layer "F.Fab")
			(hide yes)
			(effects
				(font
					(size 1.016 1.016)
					(thickness 0.1524)
				)
			)
		)
		(duplicate_pad_numbers_are_jumpers no)
		(fp_line
			(start 0.508 -0.9398)
			(end -0.508 -0.9398)
			(stroke
				(width 0.1524)
				(type default)
			)
			(layer "F.SilkS")
		)
		(fp_line
			(start -0.508 -0.9398)
			(end -0.508 0.9398)
			(stroke
				(width 0.1524)
				(type default)
			)
			(layer "F.SilkS")
		)
		(fp_rect
			(start -0.508 0.9398)
			(end 0.508 -0.9398)
			(stroke
				(width 0)
				(type default)
			)
			(fill no)
			(layer "F.CrtYd")
		)
		(fp_rect
			(start -0.508 0.9398)
			(end 0.508 -0.9398)
			(stroke
				(width 0)
				(type default)
			)
			(fill no)
			(layer "F.Fab")
		)
		(pad "1" smd custom
			(at 0 -0.4445 180)
			(size 0.1397 0.1397)
			(layers "F.Cu" "F.Mask" "F.Paste")
			(net "P3V3")
			(options
				(clearance outline)
				(anchor circle)
			)
			(primitives
				(gr_poly
					(pts
						(arc
							(start -0.1778 -0.2794)
							(mid -0.249642 -0.249642)
							(end -0.2794 -0.1778)
						)
						(arc
							(start -0.2794 0.1778)
							(mid -0.249642 0.249642)
							(end -0.1778 0.2794)
						)
						(arc
							(start 0.1778 0.2794)
							(mid 0.249642 0.249642)
							(end 0.2794 0.1778)
						)
						(arc
							(start 0.2794 -0.1778)
							(mid 0.249642 -0.249642)
							(end 0.1778 -0.2794)
						)
					)
					(width 0)
					(fill yes)
				)
			)
		)
		(pad "2" smd custom
			(at 0 0.4445 180)
			(size 0.1397 0.1397)
			(layers "F.Cu" "F.Mask" "F.Paste")
			(net "I2C_DRIVE_INS_SCL5")
			(options
				(clearance outline)
				(anchor circle)
			)
			(primitives
				(gr_poly
					(pts
						(arc
							(start -0.1778 -0.2794)
							(mid -0.249642 -0.249642)
							(end -0.2794 -0.1778)
						)
						(arc
							(start -0.2794 0.1778)
							(mid -0.249642 0.249642)
							(end -0.1778 0.2794)
						)
						(arc
							(start 0.1778 0.2794)
							(mid 0.249642 0.249642)
							(end 0.2794 0.1778)
						)
						(arc
							(start 0.2794 -0.1778)
							(mid 0.249642 -0.249642)
							(end 0.1778 -0.2794)
						)
					)
					(width 0)
					(fill yes)
				)
			)
		)
	)
	(footprint ""
		(layer "F.Cu")
		(at 172.339 -59.817)
		(property "Reference" "R252"
			(at 0 0 0)
			(layer "F.SilkS")
			(hide yes)
			(effects
				(font
					(size 1.27 1.27)
				)
			)
		)
		(property "Value" "10KR2F-2-GP"
			(at 0.064008 -3.993896 0)
			(unlocked yes)
			(layer "F.Fab")
			(hide yes)
			(effects
				(font
					(size 1.016 1.016)
					(thickness 0.1524)
				)
			)
		)
		(property "Device Type" "R402H16"
			(at 0.064008 -5.517896 0)
			(unlocked yes)
			(layer "F.Fab")
			(hide yes)
			(effects
				(font
					(size 1.016 1.016)
					(thickness 0.1524)
				)
			)
		)
		(duplicate_pad_numbers_are_jumpers no)
		(fp_line
			(start -0.508 -0.9398)
			(end -0.508 0.9398)
			(stroke
				(width 0.1524)
				(type default)
			)
			(layer "F.SilkS")
		)
		(fp_line
			(start 0.508 -0.9398)
			(end -0.508 -0.9398)
			(stroke
				(width 0.1524)
				(type default)
			)
			(layer "F.SilkS")
		)
		(fp_rect
			(start -0.508 0.9398)
			(end 0.508 -0.9398)
			(stroke
				(width 0)
				(type default)
			)
			(fill no)
			(layer "F.CrtYd")
		)
		(fp_rect
			(start -0.508 0.9398)
			(end 0.508 -0.9398)
			(stroke
				(width 0)
				(type default)
			)
			(fill no)
			(layer "F.Fab")
		)
		(pad "1" smd custom
			(at 0 -0.4445)
			(size 0.1397 0.1397)
			(layers "F.Cu" "F.Mask" "F.Paste")
			(net "P1V8_C")
			(options
				(clearance outline)
				(anchor circle)
			)
			(primitives
				(gr_poly
					(pts
						(arc
							(start -0.1778 -0.2794)
							(mid -0.249642 -0.249642)
							(end -0.2794 -0.1778)
						)
						(arc
							(start -0.2794 0.1778)
							(mid -0.249642 0.249642)
							(end -0.1778 0.2794)
						)
						(arc
							(start 0.1778 0.2794)
							(mid 0.249642 0.249642)
							(end 0.2794 0.1778)
						)
						(arc
							(start 0.2794 -0.1778)
							(mid 0.249642 -0.249642)
							(end 0.1778 -0.2794)
						)
					)
					(width 0)
					(fill yes)
				)
			)
		)
		(pad "2" smd custom
			(at 0 0.4445)
			(size 0.1397 0.1397)
			(layers "F.Cu" "F.Mask" "F.Paste")
			(net "LSI_TN")
			(options
				(clearance outline)
				(anchor circle)
			)
			(primitives
				(gr_poly
					(pts
						(arc
							(start -0.1778 -0.2794)
							(mid -0.249642 -0.249642)
							(end -0.2794 -0.1778)
						)
						(arc
							(start -0.2794 0.1778)
							(mid -0.249642 0.249642)
							(end -0.1778 0.2794)
						)
						(arc
							(start 0.1778 0.2794)
							(mid 0.249642 0.249642)
							(end 0.2794 0.1778)
						)
						(arc
							(start 0.2794 -0.1778)
							(mid 0.249642 -0.249642)
							(end 0.1778 -0.2794)
						)
					)
					(width 0)
					(fill yes)
				)
			)
		)
	)
	(footprint ""
		(layer "F.Cu")
		(at 148.631148 -44.257214 102)
		(property "Reference" "C338"
			(at 0 0 102)
			(layer "F.SilkS")
			(hide yes)
			(effects
				(font
					(size 1.27 1.27)
				)
			)
		)
		(property "Value" "SCD01U16V1KX-GP"
			(at -2.832048 -1.739777 102)
			(unlocked yes)
			(layer "F.Fab")
			(hide yes)
			(effects
				(font
					(size 1.016 1.016)
					(thickness 0.1524)
				)
			)
		)
		(property "Device Type" "C0201H13"
			(at -2.832174 -3.263834 102)
			(unlocked yes)
			(layer "F.Fab")
			(hide yes)
			(effects
				(font
					(size 1.016 1.016)
					(thickness 0.1524)
				)
			)
		)
		(duplicate_pad_numbers_are_jumpers no)
		(fp_poly
			(pts
				(xy -0.279454 -0.647706) (xy 0.279346 -0.647706) (xy 0.279346 0.647694) (xy -0.279454 0.647694)
			)
			(stroke
				(width 0)
				(type default)
			)
			(fill no)
			(layer "F.CrtYd")
		)
		(fp_poly
			(pts
				(xy -0.279454 -0.647706) (xy 0.279346 -0.647706) (xy 0.279346 0.647694) (xy -0.279454 0.647694)
			)
			(stroke
				(width 0)
				(type default)
			)
			(fill no)
			(layer "F.Fab")
		)
		(pad "1" smd custom
			(at -0.000001 -0.2794 102)
			(size 0.0762 0.0762)
			(layers "F.Cu" "F.Mask" "F.Paste")
			(net "PHY_SCC_TO_IOC_44_DN")
			(options
				(clearance outline)
				(anchor circle)
			)
			(primitives
				(gr_poly
					(pts
						(arc
							(start 0.1524 -0.127)
							(mid 0.137521 -0.162921)
							(end 0.1016 -0.1778)
						)
						(arc
							(start -0.1016 -0.1778)
							(mid -0.137521 -0.162921)
							(end -0.1524 -0.127)
						)
						(arc
							(start -0.1524 0.127)
							(mid -0.137521 0.162921)
							(end -0.1016 0.1778)
						)
						(arc
							(start 0.1016 0.1778)
							(mid 0.137521 0.162921)
							(end 0.1524 0.127)
						)
					)
					(width 0)
					(fill yes)
				)
			)
		)
		(pad "2" smd custom
			(at 0.000001 0.2794 102)
			(size 0.0762 0.0762)
			(layers "F.Cu" "F.Mask" "F.Paste")
			(net "PHY_SCC_TO_IOC_C_44_DN")
			(options
				(clearance outline)
				(anchor circle)
			)
			(primitives
				(gr_poly
					(pts
						(arc
							(start 0.1524 -0.127)
							(mid 0.137521 -0.162921)
							(end 0.1016 -0.1778)
						)
						(arc
							(start -0.1016 -0.1778)
							(mid -0.137521 -0.162921)
							(end -0.1524 -0.127)
						)
						(arc
							(start -0.1524 0.127)
							(mid -0.137521 0.162921)
							(end -0.1016 0.1778)
						)
						(arc
							(start 0.1016 0.1778)
							(mid 0.137521 0.162921)
							(end 0.1524 0.127)
						)
					)
					(width 0)
					(fill yes)
				)
			)
		)
	)
	(footprint ""
		(layer "F.Cu")
		(at 123.317 -112.62868)
		(property "Reference" "TP22"
			(at 0 0 0)
			(layer "F.SilkS")
			(hide yes)
			(effects
				(font
					(size 1.27 1.27)
				)
			)
		)
		(property "Value" "TPAD28-2-GP"
			(at -0.0127 -1.6637 0)
			(unlocked yes)
			(layer "F.Fab")
			(hide yes)
			(effects
				(font
					(size 1.016 1.016)
					(thickness 0.1524)
				)
			)
		)
		(property "Device Type" "TPAD28"
			(at -0.0127 -3.1877 0)
			(unlocked yes)
			(layer "F.Fab")
			(hide yes)
			(effects
				(font
					(size 1.016 1.016)
					(thickness 0.1524)
				)
			)
		)
		(duplicate_pad_numbers_are_jumpers no)
		(fp_poly
			(pts
				(arc
					(start 0.3556 0)
					(mid -0.3556 0)
					(end 0.3556 0)
				)
			)
			(stroke
				(width 0)
				(type default)
			)
			(fill no)
			(layer "F.CrtYd")
		)
		(fp_poly
			(pts
				(arc
					(start 0.6096 0)
					(mid -0.6096 0)
					(end 0.6096 0)
				)
			)
			(stroke
				(width 0)
				(type default)
			)
			(fill no)
			(layer "F.Fab")
		)
		(pad "1" smd circle
			(at 0 0)
			(size 0.7112 0.7112)
			(layers "F.Cu" "F.Mask" "F.Paste")
			(net "INT_A2_CONN1")
		)
	)
	(footprint ""
		(layer "F.Cu")
		(at 37.8206 -49.7332 180)
		(property "Reference" "C564"
			(at 0 0 180)
			(layer "F.SilkS")
			(hide yes)
			(effects
				(font
					(size 1.27 1.27)
				)
			)
		)
		(property "Value" "SC10U16V5KX-7-GP-U"
			(at -0.0762 -6.1214 180)
			(unlocked yes)
			(layer "F.Fab")
			(hide yes)
			(effects
				(font
					(size 1.016 1.016)
					(thickness 0.1524)
				)
			)
		)
		(property "Device Type" "C805H58"
			(at -0.0762 -8.1534 180)
			(unlocked yes)
			(layer "F.Fab")
			(hide yes)
			(effects
				(font
					(size 1.016 1.016)
					(thickness 0.1524)
				)
			)
		)
		(duplicate_pad_numbers_are_jumpers no)
		(fp_line
			(start 0.635 0)
			(end -0.635 0)
			(stroke
				(width 0.508)
				(type default)
			)
			(layer "F.SilkS")
		)
		(fp_rect
			(start -0.9652 1.778)
			(end 0.9652 -1.778)
			(stroke
				(width 0)
				(type default)
			)
			(fill no)
			(layer "F.CrtYd")
		)
		(fp_poly
			(pts
				(xy -0.9652 -1.778) (xy 0.9652 -1.778) (xy 0.9652 1.778) (xy -0.9652 1.778)
			)
			(stroke
				(width 0)
				(type default)
			)
			(fill no)
			(layer "F.Fab")
		)
		(pad "1" smd rect
			(at 0 -0.9652 180)
			(size 1.397 1.143)
			(layers "F.Cu" "F.Mask" "F.Paste")
			(net "P12V_STBY_VIN_Q7")
		)
		(pad "2" smd rect
			(at 0 0.9652 180)
			(size 1.397 1.143)
			(layers "F.Cu" "F.Mask" "F.Paste")
			(net "GND")
		)
	)
	(footprint ""
		(layer "F.Cu")
		(at 151.765 -110.363 90)
		(property "Reference" "C710"
			(at 0 0 90)
			(layer "F.SilkS")
			(hide yes)
			(effects
				(font
					(size 1.27 1.27)
				)
			)
		)
		(property "Value" "SC2200P50V2KX-2GP"
			(at 1.1811 -2.7051 90)
			(unlocked yes)
			(layer "F.Fab")
			(hide yes)
			(effects
				(font
					(size 1.016 1.016)
					(thickness 0.1524)
				)
			)
		)
		(property "Device Type" "C402H22"
			(at 1.1811 -4.2291 90)
			(unlocked yes)
			(layer "F.Fab")
			(hide yes)
			(effects
				(font
					(size 1.016 1.016)
					(thickness 0.1524)
				)
			)
		)
		(duplicate_pad_numbers_are_jumpers no)
		(fp_rect
			(start -0.4318 0.9525)
			(end 0.4318 -0.9525)
			(stroke
				(width 0)
				(type default)
			)
			(fill no)
			(layer "F.CrtYd")
		)
		(fp_rect
			(start -0.4318 0.9525)
			(end 0.4318 -0.9525)
			(stroke
				(width 0)
				(type default)
			)
			(fill no)
			(layer "F.Fab")
		)
		(pad "1" smd custom
			(at 0 -0.4445 90)
			(size 0.1524 0.1524)
			(layers "F.Cu" "F.Mask" "F.Paste")
			(net "P1V5_E_LL")
			(options
				(clearance outline)
				(anchor circle)
			)
			(primitives
				(gr_poly
					(pts
						(arc
							(start 0.3048 -0.2032)
							(mid 0.275042 -0.275042)
							(end 0.2032 -0.3048)
						)
						(arc
							(start -0.2032 -0.3048)
							(mid -0.275042 -0.275042)
							(end -0.3048 -0.2032)
						)
						(arc
							(start -0.3048 0.2032)
							(mid -0.275042 0.275042)
							(end -0.2032 0.3048)
						)
						(arc
							(start 0.2032 0.3048)
							(mid 0.275042 0.275042)
							(end 0.3048 0.2032)
						)
					)
					(width 0)
					(fill yes)
				)
			)
		)
		(pad "2" smd custom
			(at 0 0.4445 90)
			(size 0.1524 0.1524)
			(layers "F.Cu" "F.Mask" "F.Paste")
			(net "P1V5_E_SNB")
			(options
				(clearance outline)
				(anchor circle)
			)
			(primitives
				(gr_poly
					(pts
						(arc
							(start 0.3048 -0.2032)
							(mid 0.275042 -0.275042)
							(end 0.2032 -0.3048)
						)
						(arc
							(start -0.2032 -0.3048)
							(mid -0.275042 -0.275042)
							(end -0.3048 -0.2032)
						)
						(arc
							(start -0.3048 0.2032)
							(mid -0.275042 0.275042)
							(end -0.2032 0.3048)
						)
						(arc
							(start 0.2032 0.3048)
							(mid 0.275042 0.275042)
							(end 0.3048 0.2032)
						)
					)
					(width 0)
					(fill yes)
				)
			)
		)
	)
	(footprint ""
		(layer "F.Cu")
		(at 44.831 -43.8404 180)
		(property "Reference" "R481"
			(at 0 0 180)
			(layer "F.SilkS")
			(hide yes)
			(effects
				(font
					(size 1.27 1.27)
				)
			)
		)
		(property "Value" "0R3J-0-U-GP"
			(at -0.0254 -2.5146 180)
			(unlocked yes)
			(layer "F.Fab")
			(hide yes)
			(effects
				(font
					(size 1.016 1.016)
					(thickness 0.1524)
				)
			)
		)
		(property "Device Type" "R603H22"
			(at -0.0254 -4.0386 180)
			(unlocked yes)
			(layer "F.Fab")
			(hide yes)
			(effects
				(font
					(size 1.016 1.016)
					(thickness 0.1524)
				)
			)
		)
		(duplicate_pad_numbers_are_jumpers no)
		(fp_line
			(start 0.2032 0)
			(end 0.4826 0)
			(stroke
				(width 0.2032)
				(type default)
			)
			(layer "F.SilkS")
		)
		(fp_line
			(start -0.4826 0)
			(end -0.2032 0)
			(stroke
				(width 0.2032)
				(type default)
			)
			(layer "F.SilkS")
		)
		(fp_rect
			(start -0.5842 1.3335)
			(end 0.5842 -1.3335)
			(stroke
				(width 0)
				(type default)
			)
			(fill no)
			(layer "F.CrtYd")
		)
		(fp_rect
			(start -0.5842 1.3335)
			(end 0.5842 -1.3335)
			(stroke
				(width 0)
				(type default)
			)
			(fill no)
			(layer "F.Fab")
		)
		(pad "1" smd custom
			(at 0 -0.762 180)
			(size 0.2159 0.2159)
			(layers "F.Cu" "F.Mask" "F.Paste")
			(net "P0V9_DH")
			(options
				(clearance outline)
				(anchor circle)
			)
			(primitives
				(gr_poly
					(pts
						(arc
							(start -0.3302 -0.4318)
							(mid -0.402042 -0.402042)
							(end -0.4318 -0.3302)
						)
						(arc
							(start -0.4318 0.3302)
							(mid -0.402042 0.402042)
							(end -0.3302 0.4318)
						)
						(arc
							(start 0.3302 0.4318)
							(mid 0.402042 0.402042)
							(end 0.4318 0.3302)
						)
						(arc
							(start 0.4318 -0.3302)
							(mid 0.402042 -0.402042)
							(end 0.3302 -0.4318)
						)
					)
					(width 0)
					(fill yes)
				)
			)
		)
		(pad "2" smd custom
			(at 0 0.762 180)
			(size 0.2159 0.2159)
			(layers "F.Cu" "F.Mask" "F.Paste")
			(net "P0V9_TG")
			(options
				(clearance outline)
				(anchor circle)
			)
			(primitives
				(gr_poly
					(pts
						(arc
							(start -0.3302 -0.4318)
							(mid -0.402042 -0.402042)
							(end -0.4318 -0.3302)
						)
						(arc
							(start -0.4318 0.3302)
							(mid -0.402042 0.402042)
							(end -0.3302 0.4318)
						)
						(arc
							(start 0.3302 0.4318)
							(mid 0.402042 0.402042)
							(end 0.4318 0.3302)
						)
						(arc
							(start 0.4318 -0.3302)
							(mid 0.402042 -0.402042)
							(end 0.3302 -0.4318)
						)
					)
					(width 0)
					(fill yes)
				)
			)
		)
	)
	(footprint ""
		(layer "F.Cu")
		(at 186.508644 -56.571642 180)
		(property "Reference" "R223"
			(at 0 0 180)
			(layer "F.SilkS")
			(hide yes)
			(effects
				(font
					(size 1.27 1.27)
				)
			)
		)
		(property "Value" "10KR2F-2-GP"
			(at 0.064008 -3.993896 180)
			(unlocked yes)
			(layer "F.Fab")
			(hide yes)
			(effects
				(font
					(size 1.016 1.016)
					(thickness 0.1524)
				)
			)
		)
		(property "Device Type" "R402H16"
			(at 0.064008 -5.517896 180)
			(unlocked yes)
			(layer "F.Fab")
			(hide yes)
			(effects
				(font
					(size 1.016 1.016)
					(thickness 0.1524)
				)
			)
		)
		(duplicate_pad_numbers_are_jumpers no)
		(fp_line
			(start 0.508 -0.9398)
			(end -0.508 -0.9398)
			(stroke
				(width 0.1524)
				(type default)
			)
			(layer "F.SilkS")
		)
		(fp_line
			(start -0.508 -0.9398)
			(end -0.508 0.9398)
			(stroke
				(width 0.1524)
				(type default)
			)
			(layer "F.SilkS")
		)
		(fp_rect
			(start -0.508 0.9398)
			(end 0.508 -0.9398)
			(stroke
				(width 0)
				(type default)
			)
			(fill no)
			(layer "F.CrtYd")
		)
		(fp_rect
			(start -0.508 0.9398)
			(end 0.508 -0.9398)
			(stroke
				(width 0)
				(type default)
			)
			(fill no)
			(layer "F.Fab")
		)
		(pad "1" smd custom
			(at 0 -0.4445 180)
			(size 0.1397 0.1397)
			(layers "F.Cu" "F.Mask" "F.Paste")
			(net "XM_ADDR_2")
			(options
				(clearance outline)
				(anchor circle)
			)
			(primitives
				(gr_poly
					(pts
						(arc
							(start -0.1778 -0.2794)
							(mid -0.249642 -0.249642)
							(end -0.2794 -0.1778)
						)
						(arc
							(start -0.2794 0.1778)
							(mid -0.249642 0.249642)
							(end -0.1778 0.2794)
						)
						(arc
							(start 0.1778 0.2794)
							(mid 0.249642 0.249642)
							(end 0.2794 0.1778)
						)
						(arc
							(start 0.2794 -0.1778)
							(mid 0.249642 -0.249642)
							(end 0.1778 -0.2794)
						)
					)
					(width 0)
					(fill yes)
				)
			)
		)
		(pad "2" smd custom
			(at 0 0.4445 180)
			(size 0.1397 0.1397)
			(layers "F.Cu" "F.Mask" "F.Paste")
			(net "GND")
			(options
				(clearance outline)
				(anchor circle)
			)
			(primitives
				(gr_poly
					(pts
						(arc
							(start -0.1778 -0.2794)
							(mid -0.249642 -0.249642)
							(end -0.2794 -0.1778)
						)
						(arc
							(start -0.2794 0.1778)
							(mid -0.249642 0.249642)
							(end -0.1778 0.2794)
						)
						(arc
							(start 0.1778 0.2794)
							(mid 0.249642 0.249642)
							(end 0.2794 0.1778)
						)
						(arc
							(start 0.2794 -0.1778)
							(mid 0.249642 -0.249642)
							(end 0.1778 -0.2794)
						)
					)
					(width 0)
					(fill yes)
				)
			)
		)
	)
)
